(kicad_pcb
	(version 20260206)
	(generator "pcbnew")
	(generator_version "10.0")
	(general
		(thickness 0.77098)
		(legacy_teardrops no)
	)
	(paper "A4")
	(title_block
		(title "gnss-m2-zed-f9t — M2_ZED-F9T_MODULE.PcbDoc")
		(comment 1 "Time Appliance Project (Time Card) / footprints 32-36 of 36")
	)
	(layers
		(0 "F.Cu" signal "L01-Top Layer")
		(4 "In1.Cu" signal "L02-Inner Layer")
		(6 "In2.Cu" signal "L03-Inner Layer")
		(2 "B.Cu" signal "L04-Bottom Layer")
		(9 "F.Adhes" user "F.Adhesive")
		(11 "B.Adhes" user "B.Adhesive")
		(13 "F.Paste" user "Top Paste")
		(15 "B.Paste" user "Bottom Paste")
		(5 "F.SilkS" user "Top Overlay")
		(7 "B.SilkS" user "Bottom Overlay")
		(1 "F.Mask" user "Top Solder")
		(3 "B.Mask" user "Bottom Solder")
		(17 "Dwgs.User" user "User.Drawings")
		(19 "Cmts.User" user "User.Comments")
		(21 "Eco1.User" user "User.Eco1")
		(23 "Eco2.User" user "User.Eco2")
		(25 "Edge.Cuts" user)
		(27 "Margin" user)
		(31 "F.CrtYd" user "Top Courtyard")
		(29 "B.CrtYd" user "Bottom Courtyard")
		(35 "F.Fab" user "Top Component Outline")
		(33 "B.Fab" user "Bottom Component Outline 2")
	)
	(footprint "Vault:FP-RMCF0402-MFG"
		(layer "F.Cu")
		(at 140.101105 91.6036 -90)
		(property "Reference" "R17"
			(at -0.1 4.190519 90)
			(unlocked yes)
			(layer "F.SilkS")
			(effects
				(font
					(face "Arial")
					(size 0.96012 0.96012)
					(thickness 0.254)
				)
			)
		)
		(property "Value" "1k"
			(at -2.286231 0.46957 180)
			(unlocked yes)
			(layer "F.SilkS")
			(hide yes)
			(effects
				(font
					(face "Arial")
					(size 0.96012 0.96012)
					(thickness 0.254)
				)
			)
		)
		(sheetname "02-Antenna_Supervisor")
		(sheetfile "02-Antenna_Supervisor.kicad_sch")
		(duplicate_pad_numbers_are_jumpers no)
		(fp_line
			(start -0.85 0.4)
			(end -0.85 -0.4)
			(stroke
				(width 0.2)
				(type solid)
			)
			(layer "F.CrtYd")
		)
		(fp_line
			(start 0.85 0.4)
			(end -0.85 0.4)
			(stroke
				(width 0.2)
				(type solid)
			)
			(layer "F.CrtYd")
		)
		(fp_line
			(start 0.85 0.4)
			(end 0.85 -0.4)
			(stroke
				(width 0.2)
				(type solid)
			)
			(layer "F.CrtYd")
		)
		(fp_line
			(start 0.85 -0.4)
			(end -0.85 -0.4)
			(stroke
				(width 0.2)
				(type solid)
			)
			(layer "F.CrtYd")
		)
		(fp_line
			(start 0 0.5)
			(end 0 -0.5)
			(stroke
				(width 0.1)
				(type solid)
			)
			(layer "F.Fab")
		)
		(fp_line
			(start -0.85 0.4)
			(end -0.85 -0.4)
			(stroke
				(width 0.2)
				(type solid)
			)
			(layer "F.Fab")
		)
		(fp_line
			(start 0.85 0.4)
			(end -0.85 0.4)
			(stroke
				(width 0.2)
				(type solid)
			)
			(layer "F.Fab")
		)
		(fp_line
			(start 0.85 0.4)
			(end 0.85 -0.4)
			(stroke
				(width 0.2)
				(type solid)
			)
			(layer "F.Fab")
		)
		(fp_line
			(start 0.5 0)
			(end -0.5 0)
			(stroke
				(width 0.1)
				(type solid)
			)
			(layer "F.Fab")
		)
		(fp_line
			(start 0.85 -0.4)
			(end -0.85 -0.4)
			(stroke
				(width 0.2)
				(type solid)
			)
			(layer "F.Fab")
		)
		(fp_text user "${REFERENCE}"
			(at -0.00001 0.10711 270)
			(unlocked yes)
			(layer "F.Fab")
			(effects
				(font
					(face "Arial")
					(size 0.63 0.63)
					(thickness 0.1)
				)
				(justify left bottom)
			)
		)
		(pad "1" smd rect
			(at -0.5 0 270)
			(size 0.5 0.6)
			(layers "F.Cu" "F.Mask" "F.Paste")
			(net "ANT_DET")
			(solder_mask_margin 0)
			(solder_paste_margin 0)
		)
		(pad "2" smd rect
			(at 0.5 0 270)
			(size 0.5 0.6)
			(layers "F.Cu" "F.Mask" "F.Paste")
			(net "+3V3")
			(solder_mask_margin 0)
			(solder_paste_margin 0)
		)
	)
	(footprint "Vault:RESC1005X40X25NL05T10"
		(layer "F.Cu")
		(at 144.401105 117.9036 -90)
		(property "Reference" "R12"
			(at 0 1.495704 90)
			(unlocked yes)
			(layer "F.SilkS")
			(effects
				(font
					(face "Arial")
					(size 0.48006 0.48006)
					(thickness 0.254)
				)
			)
		)
		(property "Value" "0_5%_0402"
			(at -2.385831 6.512925 180)
			(unlocked yes)
			(layer "F.SilkS")
			(hide yes)
			(effects
				(font
					(face "Arial")
					(size 0.96012 0.96012)
					(thickness 0.254)
				)
			)
		)
		(sheetname "03-M2_GoldFingers")
		(sheetfile "03-M2_GoldFingers.kicad_sch")
		(duplicate_pad_numbers_are_jumpers no)
		(fp_line
			(start -0.9 0.45)
			(end -0.9 -0.45)
			(stroke
				(width 0.05)
				(type solid)
			)
			(layer "F.CrtYd")
		)
		(fp_line
			(start 0.9 0.45)
			(end -0.9 0.45)
			(stroke
				(width 0.05)
				(type solid)
			)
			(layer "F.CrtYd")
		)
		(fp_line
			(start 0.9 0.45)
			(end 0.9 -0.45)
			(stroke
				(width 0.05)
				(type solid)
			)
			(layer "F.CrtYd")
		)
		(fp_line
			(start 0 0.275)
			(end 0 -0.275)
			(stroke
				(width 0.1)
				(type solid)
			)
			(layer "F.CrtYd")
		)
		(fp_line
			(start 0.275 0)
			(end -0.275 0)
			(stroke
				(width 0.1)
				(type solid)
			)
			(layer "F.CrtYd")
		)
		(fp_line
			(start 0.9 -0.45)
			(end -0.9 -0.45)
			(stroke
				(width 0.05)
				(type solid)
			)
			(layer "F.CrtYd")
		)
		(pad "1" smd rect
			(at -0.425 0)
			(size 0.55 0.6)
			(layers "F.Cu" "F.Mask" "F.Paste")
			(net "RST_GPS")
		)
		(pad "2" smd rect
			(at 0.425 0)
			(size 0.55 0.6)
			(layers "F.Cu" "F.Mask" "F.Paste")
			(net "NetJ1_67")
		)
	)
	(footprint "Vault:DCK0005A_N"
		(layer "F.Cu")
		(at 142.601105 86.3306 90)
		(property "Reference" "U4"
			(at 0.3 2.301089 270)
			(unlocked yes)
			(layer "F.SilkS")
			(effects
				(font
					(face "Arial")
					(size 0.96012 0.96012)
					(thickness 0.254)
				)
			)
		)
		(property "Value" "LPV511MGX/NOPB"
			(at 8.59461 2.715911 90)
			(unlocked yes)
			(layer "F.SilkS")
			(hide yes)
			(effects
				(font
					(face "Arial")
					(size 0.96012 0.96012)
					(thickness 0.254)
				)
			)
		)
		(sheetname "02-Antenna_Supervisor")
		(sheetfile "02-Antenna_Supervisor.kicad_sch")
		(duplicate_pad_numbers_are_jumpers no)
		(fp_line
			(start 0.3 -1.1)
			(end 0.3 1.1)
			(stroke
				(width 0.2)
				(type solid)
			)
			(layer "F.SilkS")
		)
		(fp_line
			(start -0.3 -1.1)
			(end 0.3 -1.1)
			(stroke
				(width 0.2)
				(type solid)
			)
			(layer "F.SilkS")
		)
		(fp_line
			(start -0.3 -1.1)
			(end -0.3 1.1)
			(stroke
				(width 0.2)
				(type solid)
			)
			(layer "F.SilkS")
		)
		(fp_line
			(start -0.3 1.1)
			(end 0.3 1.1)
			(stroke
				(width 0.2)
				(type solid)
			)
			(layer "F.SilkS")
		)
		(fp_circle
			(center -1.125 -1.4)
			(end -1 -1.4)
			(stroke
				(width 0.25)
				(type solid)
			)
			(fill no)
			(layer "F.SilkS")
		)
		(fp_line
			(start 1.8 -1.35)
			(end 1.8 1.35)
			(stroke
				(width 0.05)
				(type solid)
			)
			(layer "F.CrtYd")
		)
		(fp_line
			(start -1.8 -1.35)
			(end 1.8 -1.35)
			(stroke
				(width 0.05)
				(type solid)
			)
			(layer "F.CrtYd")
		)
		(fp_line
			(start -1.8 -1.35)
			(end -1.8 1.35)
			(stroke
				(width 0.05)
				(type solid)
			)
			(layer "F.CrtYd")
		)
		(fp_line
			(start 0 -0.5)
			(end 0 0.5)
			(stroke
				(width 0.1)
				(type solid)
			)
			(layer "F.CrtYd")
		)
		(fp_line
			(start -0.5 0)
			(end 0.5 0)
			(stroke
				(width 0.1)
				(type solid)
			)
			(layer "F.CrtYd")
		)
		(fp_line
			(start -1.8 1.35)
			(end 1.8 1.35)
			(stroke
				(width 0.05)
				(type solid)
			)
			(layer "F.CrtYd")
		)
		(pad "1" smd roundrect
			(at -1.125 -0.65 180)
			(size 0.4 0.85)
			(layers "F.Cu" "F.Mask" "F.Paste")
			(roundrect_rratio 0.125)
			(net "NetU3_1")
		)
		(pad "2" smd roundrect
			(at -1.125 0 180)
			(size 0.4 0.85)
			(layers "F.Cu" "F.Mask" "F.Paste")
			(roundrect_rratio 0.125)
			(net "GND")
		)
		(pad "3" smd roundrect
			(at -1.125 0.65 180)
			(size 0.4 0.85)
			(layers "F.Cu" "F.Mask" "F.Paste")
			(roundrect_rratio 0.125)
			(net "NetR10_1")
		)
		(pad "4" smd roundrect
			(at 1.125 0.65 180)
			(size 0.4 0.85)
			(layers "F.Cu" "F.Mask" "F.Paste")
			(roundrect_rratio 0.125)
			(net "NetC12_1")
		)
		(pad "5" smd roundrect
			(at 1.125 -0.65 180)
			(size 0.4 0.85)
			(layers "F.Cu" "F.Mask" "F.Paste")
			(roundrect_rratio 0.125)
			(net "+3V3")
		)
	)
	(footprint "Vault:FP-RMCF0402-IPC_C"
		(layer "F.Cu")
		(at 143.801105 88.6798)
		(property "Reference" "R11"
			(at 1.15 -1.267744 0)
			(unlocked yes)
			(layer "F.SilkS")
			(effects
				(font
					(face "Arial")
					(size 0.48006 0.48006)
					(thickness 0.254)
				)
			)
		)
		(property "Value" "100k"
			(at -2.353971 7.960265 270)
			(unlocked yes)
			(layer "F.SilkS")
			(hide yes)
			(effects
				(font
					(face "Arial")
					(size 0.96012 0.96012)
					(thickness 0.254)
				)
			)
		)
		(sheetname "02-Antenna_Supervisor")
		(sheetfile "02-Antenna_Supervisor.kicad_sch")
		(duplicate_pad_numbers_are_jumpers no)
		(fp_line
			(start -0.75607 -0.375)
			(end 0.75607 -0.375)
			(stroke
				(width 0.2)
				(type solid)
			)
			(layer "F.CrtYd")
		)
		(fp_line
			(start -0.75607 0.375)
			(end -0.75607 -0.375)
			(stroke
				(width 0.2)
				(type solid)
			)
			(layer "F.CrtYd")
		)
		(fp_line
			(start -0.75607 0.375)
			(end 0.75607 0.375)
			(stroke
				(width 0.2)
				(type solid)
			)
			(layer "F.CrtYd")
		)
		(fp_line
			(start 0.75607 0.375)
			(end 0.75607 -0.375)
			(stroke
				(width 0.2)
				(type solid)
			)
			(layer "F.CrtYd")
		)
		(fp_line
			(start -0.75607 -0.375)
			(end 0.75607 -0.375)
			(stroke
				(width 0.2)
				(type solid)
			)
			(layer "F.Fab")
		)
		(fp_line
			(start -0.75607 0.375)
			(end -0.75607 -0.375)
			(stroke
				(width 0.2)
				(type solid)
			)
			(layer "F.Fab")
		)
		(fp_line
			(start -0.75607 0.375)
			(end 0.75607 0.375)
			(stroke
				(width 0.2)
				(type solid)
			)
			(layer "F.Fab")
		)
		(fp_line
			(start -0.5 0)
			(end 0.5 0)
			(stroke
				(width 0.1)
				(type solid)
			)
			(layer "F.Fab")
		)
		(fp_line
			(start 0 0.5)
			(end 0 -0.5)
			(stroke
				(width 0.1)
				(type solid)
			)
			(layer "F.Fab")
		)
		(fp_line
			(start 0.75607 0.375)
			(end 0.75607 -0.375)
			(stroke
				(width 0.2)
				(type solid)
			)
			(layer "F.Fab")
		)
		(fp_text user "${REFERENCE}"
			(at -0.00001 0.10711 360)
			(unlocked yes)
			(layer "F.Fab")
			(effects
				(font
					(face "Arial")
					(size 0.63 0.63)
					(thickness 0.1)
				)
				(justify left bottom)
			)
		)
		(pad "1" smd rect
			(at -0.36554 0)
			(size 0.58106 0.47247)
			(layers "F.Cu" "F.Mask" "F.Paste")
			(net "GND")
			(solder_mask_margin 0)
			(solder_paste_margin 0)
		)
		(pad "2" smd rect
			(at 0.36554 0)
			(size 0.58106 0.47247)
			(layers "F.Cu" "F.Mask" "F.Paste")
			(net "NetR10_1")
			(solder_mask_margin 0)
			(solder_paste_margin 0)
		)
	)
	(footprint "Vault:FP-CL542-IPC_C"
		(layer "F.Cu")
		(at 148.501105 110.5036)
		(property "Reference" "C2"
			(at 0 1.119515 0)
			(unlocked yes)
			(layer "F.SilkS")
			(effects
				(font
					(face "Arial")
					(size 0.40005 0.40005)
					(thickness 0.1778)
				)
			)
		)
		(property "Value" "1uF_25V_0402"
			(at 5.52245 1.959815 0)
			(unlocked yes)
			(layer "F.SilkS")
			(hide yes)
			(effects
				(font
					(face "Arial")
					(size 0.40005 0.40005)
					(thickness 0.1778)
				)
			)
		)
		(sheetname "01-M2_ZED-F9T_MODULE")
		(sheetfile "01-M2_ZED-F9T_MODULE.kicad_sch")
		(duplicate_pad_numbers_are_jumpers no)
		(fp_line
			(start -0.63624 -0.675)
			(end 0.63624 -0.675)
			(stroke
				(width 0.2)
				(type solid)
			)
			(layer "F.SilkS")
		)
		(fp_line
			(start -0.63624 0.675)
			(end 0.63624 0.675)
			(stroke
				(width 0.2)
				(type solid)
			)
			(layer "F.SilkS")
		)
		(fp_line
			(start -0.73624 -0.375)
			(end 0.73624 -0.375)
			(stroke
				(width 0.2)
				(type solid)
			)
			(layer "F.CrtYd")
		)
		(fp_line
			(start -0.73624 0.375)
			(end -0.73624 -0.375)
			(stroke
				(width 0.2)
				(type solid)
			)
			(layer "F.CrtYd")
		)
		(fp_line
			(start -0.73624 0.375)
			(end 0.73624 0.375)
			(stroke
				(width 0.2)
				(type solid)
			)
			(layer "F.CrtYd")
		)
		(fp_line
			(start 0.73624 0.375)
			(end 0.73624 -0.375)
			(stroke
				(width 0.2)
				(type solid)
			)
			(layer "F.CrtYd")
		)
		(fp_line
			(start -0.73624 -0.375)
			(end 0.73624 -0.375)
			(stroke
				(width 0.2)
				(type solid)
			)
			(layer "F.Fab")
		)
		(fp_line
			(start -0.73624 0.375)
			(end -0.73624 -0.375)
			(stroke
				(width 0.2)
				(type solid)
			)
			(layer "F.Fab")
		)
		(fp_line
			(start -0.73624 0.375)
			(end 0.73624 0.375)
			(stroke
				(width 0.2)
				(type solid)
			)
			(layer "F.Fab")
		)
		(fp_line
			(start -0.5 0)
			(end 0.5 0)
			(stroke
				(width 0.1)
				(type solid)
			)
			(layer "F.Fab")
		)
		(fp_line
			(start -0.5 0)
			(end 0.5 0)
			(stroke
				(width 0.1)
				(type solid)
			)
			(layer "F.Fab")
		)
		(fp_line
			(start 0 0.5)
			(end 0 -0.5)
			(stroke
				(width 0.1)
				(type solid)
			)
			(layer "F.Fab")
		)
		(fp_line
			(start 0 0.5)
			(end 0 -0.5)
			(stroke
				(width 0.1)
				(type solid)
			)
			(layer "F.Fab")
		)
		(fp_line
			(start 0.73624 0.375)
			(end 0.73624 -0.375)
			(stroke
				(width 0.2)
				(type solid)
			)
			(layer "F.Fab")
		)
		(fp_text user "${REFERENCE}"
			(at 0 0.28425 360)
			(unlocked yes)
			(layer "F.Fab")
			(effects
				(font
					(face "Arial")
					(size 0.63 0.63)
					(thickness 0.1)
				)
				(justify left bottom)
			)
		)
		(pad "1" smd rect
			(at -0.37856 0)
			(size 0.51535 0.47247)
			(layers "F.Cu" "F.Mask" "F.Paste")
			(net "+3V3")
			(solder_mask_margin 0)
			(solder_paste_margin 0)
		)
		(pad "2" smd rect
			(at 0.37856 0)
			(size 0.51535 0.47247)
			(layers "F.Cu" "F.Mask" "F.Paste")
			(net "GND")
			(solder_mask_margin 0)
			(solder_paste_margin 0)
		)
	)
)
